# BASEBOARD_FAB2 (Tioga Pass) — schematic netlist excerpt (pin names and nets, part order shuffled) for the footprints in the layout excerpt that follows; sources: Cadence DE-HDL packaged netlist, KiCad conversion of Wiwynn_Tioga_Pass_MB.brd

R6P6  RES  42.2 1.0% EMPTY  pkg 0402  page 103 : A = CLK_100M_CPU1_BCLK0_DN ; B = GND
R9L4  RES  0.0 5% CHIP  pkg 0402  page 227 : A = VR_PVDDQ_KLM_PH2_VCIN ; B = P5V_STBY
U8G3  TTL1G07_A  74LVC1G07 IC  pkg SOP  page 161 : A = FAN_PWM_OUT_SYS1 ; Y = FAN_PWM_OUT_SYS1_BUF

(kicad_pcb
	(version 20260206)
	(generator "pcbnew")
	(generator_version "10.0")
	(general
		(thickness 1.6)
		(legacy_teardrops no)
	)
	(paper "A4")
	(title_block
		(title "Wiwynn_Tioga_Pass_MB.brd")
		(comment 1 "Tioga Pass / footprints 4674-4676 of 4770")
	)
	(layers
		(0 "F.Cu" signal "TOP")
		(4 "In1.Cu" signal "L2GND")
		(6 "In2.Cu" signal "L3")
		(8 "In3.Cu" signal "L4GND")
		(10 "In4.Cu" signal "L5")
		(12 "In5.Cu" signal "L6GND")
		(14 "In6.Cu" signal "L7VCC")
		(16 "In7.Cu" signal "L8VCC")
		(18 "In8.Cu" signal "L9GND")
		(20 "In9.Cu" signal "L10")
		(22 "In10.Cu" signal "L11GND")
		(24 "In11.Cu" signal "L12")
		(26 "In12.Cu" signal "L13GND")
		(2 "B.Cu" signal "BOTTOM")
		(9 "F.Adhes" user "F.Adhesive")
		(11 "B.Adhes" user "B.Adhesive")
		(13 "F.Paste" user "Package Geometry/Pastemask Top")
		(15 "B.Paste" user "Package Geometry/Pastemask Bottom")
		(5 "F.SilkS" user "Ref Des/Silkscreen Top")
		(7 "B.SilkS" user "Ref Des/Silkscreen Bottom")
		(1 "F.Mask" user "Board Geometry/Soldermask Top")
		(3 "B.Mask" user "Board Geometry/Soldermask Bottom")
		(17 "Dwgs.User" user "User.Drawings")
		(19 "Cmts.User" user "User.Comments")
		(21 "Eco1.User" user "User.Eco1")
		(23 "Eco2.User" user "User.Eco2")
		(25 "Edge.Cuts" user "Board Geometry/Outline")
		(27 "Margin" user)
		(31 "F.CrtYd" user "Package Geometry/Place Bound Top")
		(29 "B.CrtYd" user "Package Geometry/Place Bound Bottom")
		(35 "F.Fab" user "Ref Des/Assembly Top")
		(33 "B.Fab" user "Ref Des/Assembly Bottom")
	)
	(footprint ""
		(layer "B.Cu")
		(at 406.8064 2.332228)
		(property "Reference" "U8G3"
			(at -2.667 -1.29667 180)
			(unlocked yes)
			(layer "B.SilkS")
			(effects
				(font
					(size 0.7874 0.5842)
					(thickness 0.1524)
				)
				(justify left mirror)
			)
		)
		(property "Value" ""
			(at 0 0 0)
			(layer "B.Fab")
			(effects
				(font
					(size 1.27 1.27)
				)
				(justify mirror)
			)
		)
		(duplicate_pad_numbers_are_jumpers no)
		(fp_circle
			(center 0.92964 -0.05588)
			(end 1.05664 -0.05588)
			(stroke
				(width 0.254)
				(type default)
			)
			(fill no)
			(layer "B.SilkS")
		)
		(fp_poly
			(pts
				(xy -0.21463 -0.450088) (xy -1.56337 -0.450088) (xy -1.56337 1.75006) (xy -0.21463 1.75006)
			)
			(stroke
				(width 0)
				(type default)
			)
			(fill no)
			(layer "B.CrtYd")
		)
		(fp_line
			(start -1.56337 -0.450088)
			(end -1.56337 1.75006)
			(stroke
				(width 0.1)
				(type default)
			)
			(layer "B.Fab")
		)
		(fp_line
			(start -1.56337 1.75006)
			(end -0.21463 1.75006)
			(stroke
				(width 0.1)
				(type default)
			)
			(layer "B.Fab")
		)
		(fp_line
			(start -0.21463 -0.450088)
			(end -1.56337 -0.450088)
			(stroke
				(width 0.1)
				(type default)
			)
			(layer "B.Fab")
		)
		(fp_line
			(start -0.21463 1.75006)
			(end -0.21463 -0.450088)
			(stroke
				(width 0.1)
				(type default)
			)
			(layer "B.Fab")
		)
		(fp_circle
			(center 0.4699 -0.8382)
			(end 0.5969 -0.8382)
			(stroke
				(width 0.254)
				(type default)
			)
			(fill no)
			(layer "B.Fab")
		)
		(pad "1" smd rect
			(at 0 0 180)
			(size 1.016 0.381)
			(layers "B.Cu" "B.Mask" "B.Paste")
			(net "Net_6468")
		)
		(pad "2" smd rect
			(at 0 0.649986 180)
			(size 1.016 0.381)
			(layers "B.Cu" "B.Mask" "B.Paste")
			(net "FAN_PWM_OUT_SYS1")
		)
		(pad "3" smd rect
			(at 0 1.299972 180)
			(size 1.016 0.381)
			(layers "B.Cu" "B.Mask" "B.Paste")
			(net "GND")
		)
		(pad "4" smd rect
			(at -1.778 1.299972 180)
			(size 1.016 0.381)
			(layers "B.Cu" "B.Mask" "B.Paste")
			(net "FAN_PWM_OUT_SYS1_BUF")
		)
		(pad "5" smd rect
			(at -1.778 0 180)
			(size 1.016 0.381)
			(layers "B.Cu" "B.Mask" "B.Paste")
			(net "P3V3_STBY")
		)
	)
	(footprint ""
		(layer "B.Cu")
		(at 0.762 -144.8562 90)
		(property "Reference" "R9L4"
			(at 0 0 90)
			(layer "B.SilkS")
			(hide yes)
			(effects
				(font
					(size 1.27 1.27)
				)
				(justify mirror)
			)
		)
		(property "Value" ""
			(at 0 0 90)
			(layer "B.Fab")
			(effects
				(font
					(size 1.27 1.27)
				)
				(justify mirror)
			)
		)
		(duplicate_pad_numbers_are_jumpers no)
		(fp_rect
			(start 0.2794 -0.1016)
			(end -0.2794 0.9906)
			(stroke
				(width 0)
				(type default)
			)
			(fill no)
			(layer "B.CrtYd")
		)
		(fp_line
			(start 0.2794 -0.1016)
			(end 0.2794 0.9906)
			(stroke
				(width 0.1)
				(type default)
			)
			(layer "B.Fab")
		)
		(fp_line
			(start -0.2794 -0.1016)
			(end 0.2794 -0.1016)
			(stroke
				(width 0.1)
				(type default)
			)
			(layer "B.Fab")
		)
		(fp_line
			(start 0.2794 0.9906)
			(end -0.2794 0.9906)
			(stroke
				(width 0.1)
				(type default)
			)
			(layer "B.Fab")
		)
		(fp_line
			(start -0.2794 0.9906)
			(end -0.2794 -0.1016)
			(stroke
				(width 0.1)
				(type default)
			)
			(layer "B.Fab")
		)
		(pad "1" smd rect
			(at 0 0 270)
			(size 0.508 0.508)
			(layers "B.Cu" "B.Mask" "B.Paste")
			(net "VR_PVDDQ_KLM_PH2_VCIN")
		)
		(pad "2" smd rect
			(at 0 0.889 270)
			(size 0.508 0.508)
			(layers "B.Cu" "B.Mask" "B.Paste")
			(net "P5V_STBY")
		)
		(zone
			(layer "B.Cu")
			(hatch none 0.5)
			(connect_pads
				(clearance 0)
			)
			(min_thickness 0.25)
			(keepout
				(tracks not_allowed)
				(vias allowed)
				(pads allowed)
				(copperpour not_allowed)
				(footprints allowed)
			)
			(placement
				(enabled no)
				(sheetname "")
			)
			(fill
				(thermal_gap 0.5)
				(thermal_bridge_width 0.5)
				(island_removal_mode 0)
			)
			(polygon
				(pts
					(xy 1.016 -145.1102) (xy 1.016 -144.6022) (xy 1.397 -144.6022) (xy 1.397 -145.1102)
				)
			)
		)
		(zone
			(layer "B.Cu")
			(hatch none 0.5)
			(connect_pads
				(clearance 0)
			)
			(min_thickness 0.25)
			(keepout
				(tracks allowed)
				(vias not_allowed)
				(pads allowed)
				(copperpour not_allowed)
				(footprints allowed)
			)
			(placement
				(enabled no)
				(sheetname "")
			)
			(fill
				(thermal_gap 0.5)
				(thermal_bridge_width 0.5)
				(island_removal_mode 0)
			)
			(polygon
				(pts
					(xy 1.016 -145.1102) (xy 1.016 -144.6022) (xy 1.397 -144.6022) (xy 1.397 -145.1102)
				)
			)
		)
	)
	(footprint ""
		(layer "B.Cu")
		(at 167.386 -87.757)
		(property "Reference" "R6P6"
			(at 0 0 0)
			(layer "B.SilkS")
			(hide yes)
			(effects
				(font
					(size 1.27 1.27)
				)
				(justify mirror)
			)
		)
		(property "Value" ""
			(at 0 0 0)
			(layer "B.Fab")
			(effects
				(font
					(size 1.27 1.27)
				)
				(justify mirror)
			)
		)
		(duplicate_pad_numbers_are_jumpers no)
		(fp_poly
			(pts
				(xy 0.2794 -0.1016) (xy -0.2794 -0.1016) (xy -0.2794 0.9906) (xy 0.2794 0.9906)
			)
			(stroke
				(width 0)
				(type default)
			)
			(fill no)
			(layer "B.CrtYd")
		)
		(fp_line
			(start -0.2794 -0.1016)
			(end 0.2794 -0.1016)
			(stroke
				(width 0.1)
				(type default)
			)
			(layer "B.Fab")
		)
		(fp_line
			(start -0.2794 0.9906)
			(end -0.2794 -0.1016)
			(stroke
				(width 0.1)
				(type default)
			)
			(layer "B.Fab")
		)
		(fp_line
			(start 0.2794 -0.1016)
			(end 0.2794 0.9906)
			(stroke
				(width 0.1)
				(type default)
			)
			(layer "B.Fab")
		)
		(fp_line
			(start 0.2794 0.9906)
			(end -0.2794 0.9906)
			(stroke
				(width 0.1)
				(type default)
			)
			(layer "B.Fab")
		)
		(pad "1" smd rect
			(at 0 0 180)
			(size 0.508 0.508)
			(layers "B.Cu" "B.Mask" "B.Paste")
			(net "CLK_100M_CPU1_BCLK0_DN")
		)
		(pad "2" smd rect
			(at 0 0.889 180)
			(size 0.508 0.508)
			(layers "B.Cu" "B.Mask" "B.Paste")
			(net "GND")
		)
		(zone
			(layer "B.Cu")
			(hatch none 0.5)
			(connect_pads
				(clearance 0)
			)
			(min_thickness 0.25)
			(keepout
				(tracks allowed)
				(vias not_allowed)
				(pads allowed)
				(copperpour not_allowed)
				(footprints allowed)
			)
			(placement
				(enabled no)
				(sheetname "")
			)
			(fill
				(thermal_gap 0.5)
				(thermal_bridge_width 0.5)
				(island_removal_mode 0)
			)
			(polygon
				(pts
					(xy 167.64 -87.503) (xy 167.132 -87.503) (xy 167.132 -87.122) (xy 167.64 -87.122)
				)
			)
		)
		(zone
			(layer "B.Cu")
			(hatch none 0.5)
			(connect_pads
				(clearance 0)
			)
			(min_thickness 0.25)
			(keepout
				(tracks not_allowed)
				(vias allowed)
				(pads allowed)
				(copperpour not_allowed)
				(footprints allowed)
			)
			(placement
				(enabled no)
				(sheetname "")
			)
			(fill
				(thermal_gap 0.5)
				(thermal_bridge_width 0.5)
				(island_removal_mode 0)
			)
			(polygon
				(pts
					(xy 167.64 -87.122) (xy 167.132 -87.122) (xy 167.132 -87.503) (xy 167.64 -87.503)
				)
			)
		)
	)
)
